(kicad_pcb
	(version 20260206)
	(generator "pcbnew")
	(generator_version "10.0")
	(general
		(thickness 1.6)
		(legacy_teardrops no)
	)
	(paper "A4")
	(title_block
		(title "Wiwynn_Tioga_Pass_MB.brd")
		(comment 1 "Tioga Pass / footprint 1719 of 4770 (EU8A1), pads 1-41 of 41")
	)
	(layers
		(0 "F.Cu" signal "TOP")
		(4 "In1.Cu" signal "L2GND")
		(6 "In2.Cu" signal "L3")
		(8 "In3.Cu" signal "L4GND")
		(10 "In4.Cu" signal "L5")
		(12 "In5.Cu" signal "L6GND")
		(14 "In6.Cu" signal "L7VCC")
		(16 "In7.Cu" signal "L8VCC")
		(18 "In8.Cu" signal "L9GND")
		(20 "In9.Cu" signal "L10")
		(22 "In10.Cu" signal "L11GND")
		(24 "In11.Cu" signal "L12")
		(26 "In12.Cu" signal "L13GND")
		(2 "B.Cu" signal "BOTTOM")
		(9 "F.Adhes" user "F.Adhesive")
		(11 "B.Adhes" user "B.Adhesive")
		(13 "F.Paste" user "Package Geometry/Pastemask Top")
		(15 "B.Paste" user "Package Geometry/Pastemask Bottom")
		(5 "F.SilkS" user "Ref Des/Silkscreen Top")
		(7 "B.SilkS" user "Ref Des/Silkscreen Bottom")
		(1 "F.Mask" user "Board Geometry/Soldermask Top")
		(3 "B.Mask" user "Board Geometry/Soldermask Bottom")
		(17 "Dwgs.User" user "User.Drawings")
		(19 "Cmts.User" user "User.Comments")
		(21 "Eco1.User" user "User.Eco1")
		(23 "Eco2.User" user "User.Eco2")
		(25 "Edge.Cuts" user "Board Geometry/Outline")
		(27 "Margin" user)
		(31 "F.CrtYd" user "Package Geometry/Place Bound Top")
		(29 "B.CrtYd" user "Package Geometry/Place Bound Bottom")
		(35 "F.Fab" user "Ref Des/Assembly Top")
		(33 "B.Fab" user "Ref Des/Assembly Bottom")
	)
	(footprint ""
		(layer "F.Cu")
		(at 395.7828 -153.797 90)
		(property "Reference" "EU8A1"
			(at 3.40233 -2.7178 0)
			(unlocked yes)
			(layer "F.SilkS")
			(effects
				(font
					(size 0.7874 0.5842)
					(thickness 0.1524)
				)
				(justify left)
			)
		)
		(property "Value" ""
			(at 0 0 90)
			(layer "F.Fab")
			(effects
				(font
					(size 1.27 1.27)
				)
			)
		)
		(duplicate_pad_numbers_are_jumpers no)
		(pad "1" smd custom
			(at -2.4511 -1.800098 90)
			(size 0.0508 0.0508)
			(layers "F.Cu" "F.Mask" "F.Paste")
			(net "Net_351")
			(options
				(clearance outline)
				(anchor circle)
			)
			(primitives
				(gr_poly
					(pts
						(arc
							(start 0.254 -0.1016)
							(mid 0.3556 0)
							(end 0.254 0.1016)
						)
						(xy -0.3556 0.1016) (xy -0.3556 -0.1016)
					)
					(width 0)
					(fill yes)
				)
			)
		)
		(pad "2" smd custom
			(at -2.4511 -1.400048 90)
			(size 0.0508 0.0508)
			(layers "F.Cu" "F.Mask" "F.Paste")
			(net "Net_352")
			(options
				(clearance outline)
				(anchor circle)
			)
			(primitives
				(gr_poly
					(pts
						(arc
							(start 0.254 -0.1016)
							(mid 0.3556 0)
							(end 0.254 0.1016)
						)
						(xy -0.3556 0.1016) (xy -0.3556 -0.1016)
					)
					(width 0)
					(fill yes)
				)
			)
		)
		(pad "3" smd custom
			(at -2.4511 -0.999998 90)
			(size 0.0508 0.0508)
			(layers "F.Cu" "F.Mask" "F.Paste")
			(net "VR_P1V05_PCH_STBY_PWM1")
			(options
				(clearance outline)
				(anchor circle)
			)
			(primitives
				(gr_poly
					(pts
						(arc
							(start 0.254 -0.1016)
							(mid 0.3556 0)
							(end 0.254 0.1016)
						)
						(xy -0.3556 0.1016) (xy -0.3556 -0.1016)
					)
					(width 0)
					(fill yes)
				)
			)
		)
		(pad "4" smd custom
			(at -2.4511 -0.599948 90)
			(size 0.0508 0.0508)
			(layers "F.Cu" "F.Mask" "F.Paste")
			(net "Net_353")
			(options
				(clearance outline)
				(anchor circle)
			)
			(primitives
				(gr_poly
					(pts
						(arc
							(start 0.254 -0.1016)
							(mid 0.3556 0)
							(end 0.254 0.1016)
						)
						(xy -0.3556 0.1016) (xy -0.3556 -0.1016)
					)
					(width 0)
					(fill yes)
				)
			)
		)
		(pad "5" smd custom
			(at -2.4511 -0.199898 90)
			(size 0.0508 0.0508)
			(layers "F.Cu" "F.Mask" "F.Paste")
			(net "VR_PVNN_PCH_PWM1")
			(options
				(clearance outline)
				(anchor circle)
			)
			(primitives
				(gr_poly
					(pts
						(arc
							(start 0.254 -0.1016)
							(mid 0.3556 0)
							(end 0.254 0.1016)
						)
						(xy -0.3556 0.1016) (xy -0.3556 -0.1016)
					)
					(width 0)
					(fill yes)
				)
			)
		)
		(pad "6" smd custom
			(at -2.4511 0.199898 90)
			(size 0.0508 0.0508)
			(layers "F.Cu" "F.Mask" "F.Paste")
			(net "SMB_VR_STBY_LVC3_SDA")
			(options
				(clearance outline)
				(anchor circle)
			)
			(primitives
				(gr_poly
					(pts
						(arc
							(start 0.254 -0.1016)
							(mid 0.3556 0)
							(end 0.254 0.1016)
						)
						(xy -0.3556 0.1016) (xy -0.3556 -0.1016)
					)
					(width 0)
					(fill yes)
				)
			)
		)
		(pad "7" smd custom
			(at -2.4511 0.599948 90)
			(size 0.0508 0.0508)
			(layers "F.Cu" "F.Mask" "F.Paste")
			(net "SMB_VR_STBY_LVC3_SCL")
			(options
				(clearance outline)
				(anchor circle)
			)
			(primitives
				(gr_poly
					(pts
						(arc
							(start 0.254 -0.1016)
							(mid 0.3556 0)
							(end 0.254 0.1016)
						)
						(xy -0.3556 0.1016) (xy -0.3556 -0.1016)
					)
					(width 0)
					(fill yes)
				)
			)
		)
		(pad "8" smd custom
			(at -2.4511 0.999998 90)
			(size 0.0508 0.0508)
			(layers "F.Cu" "F.Mask" "F.Paste")
			(net "Net_289")
			(options
				(clearance outline)
				(anchor circle)
			)
			(primitives
				(gr_poly
					(pts
						(arc
							(start 0.254 -0.1016)
							(mid 0.3556 0)
							(end 0.254 0.1016)
						)
						(xy -0.3556 0.1016) (xy -0.3556 -0.1016)
					)
					(width 0)
					(fill yes)
				)
			)
		)
		(pad "9" smd custom
			(at -2.4511 1.400048 90)
			(size 0.0508 0.0508)
			(layers "F.Cu" "F.Mask" "F.Paste")
			(net "PWRGD_PVNN_PCH_R")
			(options
				(clearance outline)
				(anchor circle)
			)
			(primitives
				(gr_poly
					(pts
						(arc
							(start 0.254 -0.1016)
							(mid 0.3556 0)
							(end 0.254 0.1016)
						)
						(xy -0.3556 0.1016) (xy -0.3556 -0.1016)
					)
					(width 0)
					(fill yes)
				)
			)
		)
		(pad "10" smd custom
			(at -2.4511 1.800098 90)
			(size 0.0508 0.0508)
			(layers "F.Cu" "F.Mask" "F.Paste")
			(net "VR_PVNN_PCH_VREN")
			(options
				(clearance outline)
				(anchor circle)
			)
			(primitives
				(gr_poly
					(pts
						(arc
							(start 0.254 -0.1016)
							(mid 0.3556 0)
							(end 0.254 0.1016)
						)
						(xy -0.3556 0.1016) (xy -0.3556 -0.1016)
					)
					(width 0)
					(fill yes)
				)
			)
		)
		(pad "11" smd custom
			(at -1.800098 2.4511 90)
			(size 0.0508 0.0508)
			(layers "F.Cu" "F.Mask" "F.Paste")
			(net "IRQ_PVNN_PCH_VRHOT_N")
			(options
				(clearance outline)
				(anchor circle)
			)
			(primitives
				(gr_poly
					(pts
						(arc
							(start -0.1016 -0.254)
							(mid 0 -0.3556)
							(end 0.1016 -0.254)
						)
						(xy 0.1016 0.3556) (xy -0.1016 0.3556)
					)
					(width 0)
					(fill yes)
				)
			)
		)
		(pad "12" smd custom
			(at -1.400048 2.4511 90)
			(size 0.0508 0.0508)
			(layers "F.Cu" "F.Mask" "F.Paste")
			(net "PU_PVNN_PCH_PINALRT_N")
			(options
				(clearance outline)
				(anchor circle)
			)
			(primitives
				(gr_poly
					(pts
						(arc
							(start -0.1016 -0.254)
							(mid 0 -0.3556)
							(end 0.1016 -0.254)
						)
						(xy 0.1016 0.3556) (xy -0.1016 0.3556)
					)
					(width 0)
					(fill yes)
				)
			)
		)
		(pad "13" smd custom
			(at -0.999998 2.4511 90)
			(size 0.0508 0.0508)
			(layers "F.Cu" "F.Mask" "F.Paste")
			(net "VID_PCH_CORE_PVNN_AUX_VID_0")
			(options
				(clearance outline)
				(anchor circle)
			)
			(primitives
				(gr_poly
					(pts
						(arc
							(start -0.1016 -0.254)
							(mid 0 -0.3556)
							(end 0.1016 -0.254)
						)
						(xy 0.1016 0.3556) (xy -0.1016 0.3556)
					)
					(width 0)
					(fill yes)
				)
			)
		)
		(pad "14" smd custom
			(at -0.599948 2.4511 90)
			(size 0.0508 0.0508)
			(layers "F.Cu" "F.Mask" "F.Paste")
			(net "VID_PCH_CORE_PVNN_AUX_VID_1")
			(options
				(clearance outline)
				(anchor circle)
			)
			(primitives
				(gr_poly
					(pts
						(arc
							(start -0.1016 -0.254)
							(mid 0 -0.3556)
							(end 0.1016 -0.254)
						)
						(xy 0.1016 0.3556) (xy -0.1016 0.3556)
					)
					(width 0)
					(fill yes)
				)
			)
		)
		(pad "15" smd custom
			(at -0.199898 2.4511 90)
			(size 0.0508 0.0508)
			(layers "F.Cu" "F.Mask" "F.Paste")
			(net "PU_PVNN_PCH_VCLK")
			(options
				(clearance outline)
				(anchor circle)
			)
			(primitives
				(gr_poly
					(pts
						(arc
							(start -0.1016 -0.254)
							(mid 0 -0.3556)
							(end 0.1016 -0.254)
						)
						(xy 0.1016 0.3556) (xy -0.1016 0.3556)
					)
					(width 0)
					(fill yes)
				)
			)
		)
		(pad "16" smd custom
			(at 0.199898 2.4511 90)
			(size 0.0508 0.0508)
			(layers "F.Cu" "F.Mask" "F.Paste")
			(net "PU_PVNN_PCH_VDIO")
			(options
				(clearance outline)
				(anchor circle)
			)
			(primitives
				(gr_poly
					(pts
						(arc
							(start -0.1016 -0.254)
							(mid 0 -0.3556)
							(end 0.1016 -0.254)
						)
						(xy 0.1016 0.3556) (xy -0.1016 0.3556)
					)
					(width 0)
					(fill yes)
				)
			)
		)
		(pad "17" smd custom
			(at 0.599948 2.4511 90)
			(size 0.0508 0.0508)
			(layers "F.Cu" "F.Mask" "F.Paste")
			(net "Net_267")
			(options
				(clearance outline)
				(anchor circle)
			)
			(primitives
				(gr_poly
					(pts
						(arc
							(start -0.1016 -0.254)
							(mid 0 -0.3556)
							(end 0.1016 -0.254)
						)
						(xy 0.1016 0.3556) (xy -0.1016 0.3556)
					)
					(width 0)
					(fill yes)
				)
			)
		)
		(pad "18" smd custom
			(at 0.999998 2.4511 90)
			(size 0.0508 0.0508)
			(layers "F.Cu" "F.Mask" "F.Paste")
			(net "Net_298")
			(options
				(clearance outline)
				(anchor circle)
			)
			(primitives
				(gr_poly
					(pts
						(arc
							(start -0.1016 -0.254)
							(mid 0 -0.3556)
							(end 0.1016 -0.254)
						)
						(xy 0.1016 0.3556) (xy -0.1016 0.3556)
					)
					(width 0)
					(fill yes)
				)
			)
		)
		(pad "19" smd custom
			(at 1.400048 2.4511 90)
			(size 0.0508 0.0508)
			(layers "F.Cu" "F.Mask" "F.Paste")
			(net "VR_PVNN_PCH_AVSP")
			(options
				(clearance outline)
				(anchor circle)
			)
			(primitives
				(gr_poly
					(pts
						(arc
							(start -0.1016 -0.254)
							(mid 0 -0.3556)
							(end 0.1016 -0.254)
						)
						(xy 0.1016 0.3556) (xy -0.1016 0.3556)
					)
					(width 0)
					(fill yes)
				)
			)
		)
		(pad "20" smd custom
			(at 1.800098 2.4511 90)
			(size 0.0508 0.0508)
			(layers "F.Cu" "F.Mask" "F.Paste")
			(net "VSENSE_PVNN_PCH_STBY_AVSN")
			(options
				(clearance outline)
				(anchor circle)
			)
			(primitives
				(gr_poly
					(pts
						(arc
							(start -0.1016 -0.254)
							(mid 0 -0.3556)
							(end 0.1016 -0.254)
						)
						(xy 0.1016 0.3556) (xy -0.1016 0.3556)
					)
					(width 0)
					(fill yes)
				)
			)
		)
		(pad "21" smd custom
			(at 2.4511 1.800098 90)
			(size 0.0508 0.0508)
			(layers "F.Cu" "F.Mask" "F.Paste")
			(net "VR_PVNN_PCH_AIREF1")
			(options
				(clearance outline)
				(anchor circle)
			)
			(primitives
				(gr_poly
					(pts
						(arc
							(start -0.254 0.1016)
							(mid -0.3556 0)
							(end -0.254 -0.1016)
						)
						(xy 0.3556 -0.1016) (xy 0.3556 0.1016)
					)
					(width 0)
					(fill yes)
				)
			)
		)
		(pad "22" smd custom
			(at 2.4511 1.400048 90)
			(size 0.0508 0.0508)
			(layers "F.Cu" "F.Mask" "F.Paste")
			(net "ISENSE_PVNN_PCH_PH1_IMON")
			(options
				(clearance outline)
				(anchor circle)
			)
			(primitives
				(gr_poly
					(pts
						(arc
							(start -0.254 0.1016)
							(mid -0.3556 0)
							(end -0.254 -0.1016)
						)
						(xy 0.3556 -0.1016) (xy 0.3556 0.1016)
					)
					(width 0)
					(fill yes)
				)
			)
		)
		(pad "23" smd custom
			(at 2.4511 0.999998 90)
			(size 0.0508 0.0508)
			(layers "F.Cu" "F.Mask" "F.Paste")
			(net "GND")
			(options
				(clearance outline)
				(anchor circle)
			)
			(primitives
				(gr_poly
					(pts
						(arc
							(start -0.254 0.1016)
							(mid -0.3556 0)
							(end -0.254 -0.1016)
						)
						(xy 0.3556 -0.1016) (xy 0.3556 0.1016)
					)
					(width 0)
					(fill yes)
				)
			)
		)
		(pad "24" smd custom
			(at 2.4511 0.599948 90)
			(size 0.0508 0.0508)
			(layers "F.Cu" "F.Mask" "F.Paste")
			(net "Net_354")
			(options
				(clearance outline)
				(anchor circle)
			)
			(primitives
				(gr_poly
					(pts
						(arc
							(start -0.254 0.1016)
							(mid -0.3556 0)
							(end -0.254 -0.1016)
						)
						(xy 0.3556 -0.1016) (xy 0.3556 0.1016)
					)
					(width 0)
					(fill yes)
				)
			)
		)
		(pad "25" smd custom
			(at 2.4511 0.199898 90)
			(size 0.0508 0.0508)
			(layers "F.Cu" "F.Mask" "F.Paste")
			(net "VR_P1V05_PCH_BIREF1")
			(options
				(clearance outline)
				(anchor circle)
			)
			(primitives
				(gr_poly
					(pts
						(arc
							(start -0.254 0.1016)
							(mid -0.3556 0)
							(end -0.254 -0.1016)
						)
						(xy 0.3556 -0.1016) (xy 0.3556 0.1016)
					)
					(width 0)
					(fill yes)
				)
			)
		)
		(pad "26" smd custom
			(at 2.4511 -0.199898 90)
			(size 0.0508 0.0508)
			(layers "F.Cu" "F.Mask" "F.Paste")
			(net "ISENSE_P1V05_PCH_STBY_PH1_IMON")
			(options
				(clearance outline)
				(anchor circle)
			)
			(primitives
				(gr_poly
					(pts
						(arc
							(start -0.254 0.1016)
							(mid -0.3556 0)
							(end -0.254 -0.1016)
						)
						(xy 0.3556 -0.1016) (xy 0.3556 0.1016)
					)
					(width 0)
					(fill yes)
				)
			)
		)
		(pad "27" smd custom
			(at 2.4511 -0.599948 90)
			(size 0.0508 0.0508)
			(layers "F.Cu" "F.Mask" "F.Paste")
			(net "GND")
			(options
				(clearance outline)
				(anchor circle)
			)
			(primitives
				(gr_poly
					(pts
						(arc
							(start -0.254 0.1016)
							(mid -0.3556 0)
							(end -0.254 -0.1016)
						)
						(xy 0.3556 -0.1016) (xy 0.3556 0.1016)
					)
					(width 0)
					(fill yes)
				)
			)
		)
		(pad "28" smd custom
			(at 2.4511 -0.999998 90)
			(size 0.0508 0.0508)
			(layers "F.Cu" "F.Mask" "F.Paste")
			(net "Net_355")
			(options
				(clearance outline)
				(anchor circle)
			)
			(primitives
				(gr_poly
					(pts
						(arc
							(start -0.254 0.1016)
							(mid -0.3556 0)
							(end -0.254 -0.1016)
						)
						(xy 0.3556 -0.1016) (xy 0.3556 0.1016)
					)
					(width 0)
					(fill yes)
				)
			)
		)
		(pad "29" smd custom
			(at 2.4511 -1.400048 90)
			(size 0.0508 0.0508)
			(layers "F.Cu" "F.Mask" "F.Paste")
			(net "VR_P1V05_PCH_STBY_AVSP")
			(options
				(clearance outline)
				(anchor circle)
			)
			(primitives
				(gr_poly
					(pts
						(arc
							(start -0.254 0.1016)
							(mid -0.3556 0)
							(end -0.254 -0.1016)
						)
						(xy 0.3556 -0.1016) (xy 0.3556 0.1016)
					)
					(width 0)
					(fill yes)
				)
			)
		)
		(pad "30" smd custom
			(at 2.4511 -1.800098 90)
			(size 0.0508 0.0508)
			(layers "F.Cu" "F.Mask" "F.Paste")
			(net "VSENSE_P1V05_PCH_STBY_AVSN")
			(options
				(clearance outline)
				(anchor circle)
			)
			(primitives
				(gr_poly
					(pts
						(arc
							(start -0.254 0.1016)
							(mid -0.3556 0)
							(end -0.254 -0.1016)
						)
						(xy 0.3556 -0.1016) (xy 0.3556 0.1016)
					)
					(width 0)
					(fill yes)
				)
			)
		)
		(pad "31" smd custom
			(at 1.800098 -2.4511 90)
			(size 0.0508 0.0508)
			(layers "F.Cu" "F.Mask" "F.Paste")
			(net "Net_299")
			(options
				(clearance outline)
				(anchor circle)
			)
			(primitives
				(gr_poly
					(pts
						(arc
							(start 0.1016 0.254)
							(mid 0 0.3556)
							(end -0.1016 0.254)
						)
						(xy -0.1016 -0.3556) (xy 0.1016 -0.3556)
					)
					(width 0)
					(fill yes)
				)
			)
		)
		(pad "32" smd custom
			(at 1.400048 -2.4511 90)
			(size 0.0508 0.0508)
			(layers "F.Cu" "F.Mask" "F.Paste")
			(net "PU_VR_PVNN_PCH_FAULT1")
			(options
				(clearance outline)
				(anchor circle)
			)
			(primitives
				(gr_poly
					(pts
						(arc
							(start 0.1016 0.254)
							(mid 0 0.3556)
							(end -0.1016 0.254)
						)
						(xy -0.1016 -0.3556) (xy 0.1016 -0.3556)
					)
					(width 0)
					(fill yes)
				)
			)
		)
		(pad "33" smd custom
			(at 0.999998 -2.4511 90)
			(size 0.0508 0.0508)
			(layers "F.Cu" "F.Mask" "F.Paste")
			(net "VR_PVNN_PCH_XADDR2")
			(options
				(clearance outline)
				(anchor circle)
			)
			(primitives
				(gr_poly
					(pts
						(arc
							(start 0.1016 0.254)
							(mid 0 0.3556)
							(end -0.1016 0.254)
						)
						(xy -0.1016 -0.3556) (xy 0.1016 -0.3556)
					)
					(width 0)
					(fill yes)
				)
			)
		)
		(pad "34" smd custom
			(at 0.599948 -2.4511 90)
			(size 0.0508 0.0508)
			(layers "F.Cu" "F.Mask" "F.Paste")
			(net "A_TSENSE_P1V05_PCH_STBY_TMON")
			(options
				(clearance outline)
				(anchor circle)
			)
			(primitives
				(gr_poly
					(pts
						(arc
							(start 0.1016 0.254)
							(mid 0 0.3556)
							(end -0.1016 0.254)
						)
						(xy -0.1016 -0.3556) (xy 0.1016 -0.3556)
					)
					(width 0)
					(fill yes)
				)
			)
		)
		(pad "35" smd custom
			(at 0.199898 -2.4511 90)
			(size 0.0508 0.0508)
			(layers "F.Cu" "F.Mask" "F.Paste")
			(net "A_TSENSE_PVNN_PCH_TMON")
			(options
				(clearance outline)
				(anchor circle)
			)
			(primitives
				(gr_poly
					(pts
						(arc
							(start 0.1016 0.254)
							(mid 0 0.3556)
							(end -0.1016 0.254)
						)
						(xy -0.1016 -0.3556) (xy 0.1016 -0.3556)
					)
					(width 0)
					(fill yes)
				)
			)
		)
		(pad "36" smd custom
			(at -0.199898 -2.4511 90)
			(size 0.0508 0.0508)
			(layers "F.Cu" "F.Mask" "F.Paste")
			(net "VR_PVNN_PCH_XADDR1")
			(options
				(clearance outline)
				(anchor circle)
			)
			(primitives
				(gr_poly
					(pts
						(arc
							(start 0.1016 0.254)
							(mid 0 0.3556)
							(end -0.1016 0.254)
						)
						(xy -0.1016 -0.3556) (xy 0.1016 -0.3556)
					)
					(width 0)
					(fill yes)
				)
			)
		)
		(pad "37" smd custom
			(at -0.599948 -2.4511 90)
			(size 0.0508 0.0508)
			(layers "F.Cu" "F.Mask" "F.Paste")
			(net "VR_PVNN_PCH_VINSEN")
			(options
				(clearance outline)
				(anchor circle)
			)
			(primitives
				(gr_poly
					(pts
						(arc
							(start 0.1016 0.254)
							(mid 0 0.3556)
							(end -0.1016 0.254)
						)
						(xy -0.1016 -0.3556) (xy 0.1016 -0.3556)
					)
					(width 0)
					(fill yes)
				)
			)
		)
		(pad "38" smd custom
			(at -0.999998 -2.4511 90)
			(size 0.0508 0.0508)
			(layers "F.Cu" "F.Mask" "F.Paste")
			(net "Net_268")
			(options
				(clearance outline)
				(anchor circle)
			)
			(primitives
				(gr_poly
					(pts
						(arc
							(start 0.1016 0.254)
							(mid 0 0.3556)
							(end -0.1016 0.254)
						)
						(xy -0.1016 -0.3556) (xy 0.1016 -0.3556)
					)
					(width 0)
					(fill yes)
				)
			)
		)
		(pad "39" smd custom
			(at -1.400048 -2.4511 90)
			(size 0.0508 0.0508)
			(layers "F.Cu" "F.Mask" "F.Paste")
			(net "VR_PVNN_PCH_VDD")
			(options
				(clearance outline)
				(anchor circle)
			)
			(primitives
				(gr_poly
					(pts
						(arc
							(start 0.1016 0.254)
							(mid 0 0.3556)
							(end -0.1016 0.254)
						)
						(xy -0.1016 -0.3556) (xy 0.1016 -0.3556)
					)
					(width 0)
					(fill yes)
				)
			)
		)
		(pad "40" smd custom
			(at -1.800098 -2.4511 90)
			(size 0.0508 0.0508)
			(layers "F.Cu" "F.Mask" "F.Paste")
			(net "VR_PVNN_P1V05_PCH_VD12")
			(options
				(clearance outline)
				(anchor circle)
			)
			(primitives
				(gr_poly
					(pts
						(arc
							(start 0.1016 0.254)
							(mid 0 0.3556)
							(end -0.1016 0.254)
						)
						(xy -0.1016 -0.3556) (xy 0.1016 -0.3556)
					)
					(width 0)
					(fill yes)
				)
			)
		)
		(pad "41" smd rect
			(at 0 0 90)
			(size 3.683 3.683)
			(layers "F.Cu" "F.Mask" "F.Paste")
			(net "GND")
		)
	)
)
